(kicad_pcb
	(version 20221018)
	(generator pcbnew)
	(general
    (thickness 1.7403)
  )
	(paper "A4")
	(title_block
    (title "Data Center RDIMM DDR4 Tester")
    (date "2024-09-30")
    (rev "1.2.4")
		(comment 9 "footprints 412-421 of 690")
	)
	(layers
    (0 "F.Cu" signal)
    (1 "In1.Cu" power)
    (2 "In2.Cu" signal)
    (3 "In3.Cu" power)
    (4 "In4.Cu" power)
    (5 "In5.Cu" signal)
    (6 "In6.Cu" power)
    (7 "In7.Cu" signal)
    (8 "In8.Cu" power)
    (9 "In9.Cu" signal)
    (10 "In10.Cu" power)
    (31 "B.Cu" signal)
    (32 "B.Adhes" user "B.Adhesive")
    (33 "F.Adhes" user "F.Adhesive")
    (34 "B.Paste" user)
    (35 "F.Paste" user)
    (36 "B.SilkS" user "B.Silkscreen")
    (37 "F.SilkS" user "F.Silkscreen")
    (38 "B.Mask" user)
    (39 "F.Mask" user)
    (40 "Dwgs.User" user "User.Drawings")
    (41 "Cmts.User" user "User.Comments")
    (42 "Eco1.User" user "User.Eco1")
    (43 "Eco2.User" user "User.Eco2")
    (44 "Edge.Cuts" user)
    (45 "Margin" user)
    (46 "B.CrtYd" user "B.Courtyard")
    (47 "F.CrtYd" user "F.Courtyard")
    (48 "B.Fab" user)
    (49 "F.Fab" user)
  )
	(footprint "data-center-rdimm-ddr4-tester-footprints:R_0402_1005Metric" (layer "B.Cu")
    (at 156.186328 87.810008 -90)
    (descr "Resistor SMD 0402")
    (tags "resistor SMD 0402")
    (property "Author" "Antmicro")
    (property "License" "Apache-2.0")
    (property "MPN" "CR0402-FX-2201GLF")
    (property "Manufacturer" "Bourns")
    (property "Sheetfile" "ethernet.kicad_sch")
    (property "Sheetname" "Ethernet")
    (property "Tolerance" "1%")
    (property "Val" "2k2")
    (property "ki_description" "2k2 resistor in 0402 package with 1% tolerance")
    (attr smd)
    (fp_text reference "R93" (at -1.130008 -8.063672 90) (layer "B.SilkS")
        (effects (font (size 0.7 0.7) (thickness 0.15)) (justify left bottom mirror))
    )
    (fp_text value "R_2k2_0402" (at 0 -1.4 90) (layer "B.Fab") hide
        (effects (font (size 0.7 0.7) (thickness 0.15)) (justify left bottom mirror))
    )
    (fp_text user "${REFERENCE}" (at -0.95 -3.168 90) (layer "B.Fab") hide
        (effects (font (size 0.7 0.7) (thickness 0.15)) (justify left bottom mirror))
    )
    (fp_text user "License: Apache-2.0" (at -0.95 -5.169 90) (layer "B.Fab") hide
        (effects (font (size 0.7 0.7) (thickness 0.15)) (justify left bottom mirror))
    )
    (fp_text user "Author: Antmicro" (at -0.95 -4.169 90) (layer "B.Fab") hide
        (effects (font (size 0.7 0.7) (thickness 0.15)) (justify left bottom mirror))
    )
    (fp_rect (start -0.93 0.47) (end 0.93 -0.47)
      (stroke (width 0.05) (type solid)) (fill none) (layer "B.CrtYd"))
    (fp_rect (start -0.5 0.25) (end 0.5 -0.25)
      (stroke (width 0.15) (type solid)) (fill none) (layer "B.Fab"))
    (pad "1" smd roundrect (at -0.485 0 270) (size 0.59 0.64) (layers "B.Cu" "B.Paste" "B.Mask") (roundrect_rratio 0.25)
      (net 40 "ETH_RX_CLK") (pintype "passive"))
    (pad "2" smd roundrect (at 0.485 0 270) (size 0.59 0.64) (layers "B.Cu" "B.Paste" "B.Mask") (roundrect_rratio 0.25)
      (net 9 "GND") (pintype "passive"))
  )
	(footprint "data-center-rdimm-ddr4-tester-footprints:R_0402_1005Metric" (layer "B.Cu")
    (at 156.376328 94.660008)
    (descr "Resistor SMD 0402")
    (tags "resistor SMD 0402")
    (property "Author" "Antmicro")
    (property "DNP" "DNP")
    (property "License" "Apache-2.0")
    (property "MPN" "CR0402-FX-2201GLF")
    (property "Manufacturer" "Bourns")
    (property "Sheetfile" "ethernet.kicad_sch")
    (property "Sheetname" "Ethernet")
    (property "Tolerance" "1%")
    (property "Val" "2k2")
    (property "dnp" "")
    (property "exclude_from_bom" "")
    (property "ki_description" "2k2 resistor in 0402 package with 1% tolerance")
    (attr exclude_from_pos_files exclude_from_bom)
    (fp_text reference "R94" (at 2.993672 0.349992 180) (layer "B.SilkS")
        (effects (font (size 0.7 0.7) (thickness 0.15)) (justify left bottom mirror))
    )
    (fp_text value "R_2k2_0402" (at 0 -1.4 180) (layer "B.Fab") hide
        (effects (font (size 0.7 0.7) (thickness 0.15)) (justify left bottom mirror))
    )
    (fp_text user "License: Apache-2.0" (at -0.95 -5.169 180) (layer "B.Fab") hide
        (effects (font (size 0.7 0.7) (thickness 0.15)) (justify left bottom mirror))
    )
    (fp_text user "Author: Antmicro" (at -0.95 -4.169 180) (layer "B.Fab") hide
        (effects (font (size 0.7 0.7) (thickness 0.15)) (justify left bottom mirror))
    )
    (fp_text user "${REFERENCE}" (at -0.95 -3.168 180) (layer "B.Fab") hide
        (effects (font (size 0.7 0.7) (thickness 0.15)) (justify left bottom mirror))
    )
    (fp_rect (start -0.93 0.47) (end 0.93 -0.47)
      (stroke (width 0.05) (type solid)) (fill none) (layer "B.CrtYd"))
    (fp_rect (start -0.5 0.25) (end 0.5 -0.25)
      (stroke (width 0.15) (type solid)) (fill none) (layer "B.Fab"))
    (pad "1" smd roundrect (at -0.485 0) (size 0.59 0.64) (layers "B.Cu" "B.Paste" "B.Mask") (roundrect_rratio 0.25)
      (net 30 "ETH_REF_CLK") (pintype "passive"))
    (pad "2" smd roundrect (at 0.485 0) (size 0.59 0.64) (layers "B.Cu" "B.Paste" "B.Mask") (roundrect_rratio 0.25)
      (net 9 "GND") (pintype "passive"))
  )
	(footprint "data-center-rdimm-ddr4-tester-footprints:R_0402_1005Metric" (layer "B.Cu")
    (at 166.306328 99.480008 -90)
    (descr "Resistor SMD 0402")
    (tags "resistor SMD 0402")
    (property "Author" "Antmicro")
    (property "DNP" "DNP")
    (property "License" "Apache-2.0")
    (property "MPN" "CR0402-FX-2201GLF")
    (property "Manufacturer" "Bourns")
    (property "Sheetfile" "ethernet.kicad_sch")
    (property "Sheetname" "Ethernet")
    (property "Tolerance" "1%")
    (property "Val" "2k2")
    (property "dnp" "")
    (property "exclude_from_bom" "")
    (property "ki_description" "2k2 resistor in 0402 package with 1% tolerance")
    (attr exclude_from_pos_files exclude_from_bom)
    (fp_text reference "R95" (at -1.070008 0.526328 90) (layer "B.SilkS")
        (effects (font (size 0.7 0.7) (thickness 0.15)) (justify left bottom mirror))
    )
    (fp_text value "R_2k2_0402" (at 0 -1.4 90) (layer "B.Fab") hide
        (effects (font (size 0.7 0.7) (thickness 0.15)) (justify left bottom mirror))
    )
    (fp_text user "${REFERENCE}" (at -0.95 -3.168 90) (layer "B.Fab") hide
        (effects (font (size 0.7 0.7) (thickness 0.15)) (justify left bottom mirror))
    )
    (fp_text user "License: Apache-2.0" (at -0.95 -5.169 90) (layer "B.Fab") hide
        (effects (font (size 0.7 0.7) (thickness 0.15)) (justify left bottom mirror))
    )
    (fp_text user "Author: Antmicro" (at -0.95 -4.169 90) (layer "B.Fab") hide
        (effects (font (size 0.7 0.7) (thickness 0.15)) (justify left bottom mirror))
    )
    (fp_rect (start -0.93 0.47) (end 0.93 -0.47)
      (stroke (width 0.05) (type solid)) (fill none) (layer "B.CrtYd"))
    (fp_rect (start -0.5 0.25) (end 0.5 -0.25)
      (stroke (width 0.15) (type solid)) (fill none) (layer "B.Fab"))
    (pad "1" smd roundrect (at -0.485 0 270) (size 0.59 0.64) (layers "B.Cu" "B.Paste" "B.Mask") (roundrect_rratio 0.25)
      (net 17 "LED_SPD") (pintype "passive"))
    (pad "2" smd roundrect (at 0.485 0 270) (size 0.59 0.64) (layers "B.Cu" "B.Paste" "B.Mask") (roundrect_rratio 0.25)
      (net 9 "GND") (pintype "passive"))
  )
	(footprint "data-center-rdimm-ddr4-tester-footprints:R_0402_1005Metric" (layer "B.Cu")
    (at 166.306328 95.070008 90)
    (descr "Resistor SMD 0402")
    (tags "resistor SMD 0402")
    (property "Author" "Antmicro")
    (property "DNP" "DNP")
    (property "License" "Apache-2.0")
    (property "MPN" "CR0402-FX-2201GLF")
    (property "Manufacturer" "Bourns")
    (property "Sheetfile" "ethernet.kicad_sch")
    (property "Sheetname" "Ethernet")
    (property "Tolerance" "1%")
    (property "Val" "2k2")
    (property "dnp" "")
    (property "exclude_from_bom" "")
    (property "ki_description" "2k2 resistor in 0402 package with 1% tolerance")
    (attr exclude_from_pos_files exclude_from_bom)
    (fp_text reference "R96" (at 0.830008 -0.586328 270) (layer "B.SilkS")
        (effects (font (size 0.7 0.7) (thickness 0.15)) (justify left bottom mirror))
    )
    (fp_text value "R_2k2_0402" (at 0 -1.4 270) (layer "B.Fab") hide
        (effects (font (size 0.7 0.7) (thickness 0.15)) (justify left bottom mirror))
    )
    (fp_text user "${REFERENCE}" (at -0.95 -3.168 270) (layer "B.Fab") hide
        (effects (font (size 0.7 0.7) (thickness 0.15)) (justify left bottom mirror))
    )
    (fp_text user "Author: Antmicro" (at -0.95 -4.169 270) (layer "B.Fab") hide
        (effects (font (size 0.7 0.7) (thickness 0.15)) (justify left bottom mirror))
    )
    (fp_text user "License: Apache-2.0" (at -0.95 -5.169 270) (layer "B.Fab") hide
        (effects (font (size 0.7 0.7) (thickness 0.15)) (justify left bottom mirror))
    )
    (fp_rect (start -0.93 0.47) (end 0.93 -0.47)
      (stroke (width 0.05) (type solid)) (fill none) (layer "B.CrtYd"))
    (fp_rect (start -0.5 0.25) (end 0.5 -0.25)
      (stroke (width 0.15) (type solid)) (fill none) (layer "B.Fab"))
    (pad "1" smd roundrect (at -0.485 0 90) (size 0.59 0.64) (layers "B.Cu" "B.Paste" "B.Mask") (roundrect_rratio 0.25)
      (net 16 "LED_LINK") (pintype "passive"))
    (pad "2" smd roundrect (at 0.485 0 90) (size 0.59 0.64) (layers "B.Cu" "B.Paste" "B.Mask") (roundrect_rratio 0.25)
      (net 9 "GND") (pintype "passive"))
  )
	(footprint "data-center-rdimm-ddr4-tester-footprints:R_0402_1005Metric" (layer "B.Cu")
    (at 237.65 126.065 -90)
    (descr "Resistor SMD 0402")
    (tags "resistor SMD 0402")
    (property "Author" "Antmicro")
    (property "License" "Apache-2.0")
    (property "MPN" "CR0402-FX-4701GLF")
    (property "Manufacturer" "Bourns")
    (property "Sheetfile" "config-spi.kicad_sch")
    (property "Sheetname" "Config SPI flash")
    (property "Tolerance" "1%")
    (property "Val" "4k7")
    (property "ki_description" "4k7 resistor in 0402 package with 1% tolerance")
    (attr smd)
    (fp_text reference "R28" (at -1.075 0.59 90) (layer "B.SilkS")
        (effects (font (size 0.7 0.7) (thickness 0.15)) (justify left bottom mirror))
    )
    (fp_text value "R_4k7_0402" (at 0 -1.4 90) (layer "B.Fab") hide
        (effects (font (size 0.7 0.7) (thickness 0.15)) (justify left bottom mirror))
    )
    (fp_text user "${REFERENCE}" (at -0.95 -3.168 90) (layer "B.Fab") hide
        (effects (font (size 0.7 0.7) (thickness 0.15)) (justify left bottom mirror))
    )
    (fp_text user "License: Apache-2.0" (at -0.95 -5.169 90) (layer "B.Fab") hide
        (effects (font (size 0.7 0.7) (thickness 0.15)) (justify left bottom mirror))
    )
    (fp_text user "Author: Antmicro" (at -0.95 -4.169 90) (layer "B.Fab") hide
        (effects (font (size 0.7 0.7) (thickness 0.15)) (justify left bottom mirror))
    )
    (fp_rect (start -0.93 0.47) (end 0.93 -0.47)
      (stroke (width 0.05) (type solid)) (fill none) (layer "B.CrtYd"))
    (fp_rect (start -0.5 0.25) (end 0.5 -0.25)
      (stroke (width 0.15) (type solid)) (fill none) (layer "B.Fab"))
    (pad "1" smd roundrect (at -0.485 0 270) (size 0.59 0.64) (layers "B.Cu" "B.Paste" "B.Mask") (roundrect_rratio 0.25)
      (net 143 "3V3_SYS") (pintype "passive"))
    (pad "2" smd roundrect (at 0.485 0 270) (size 0.59 0.64) (layers "B.Cu" "B.Paste" "B.Mask") (roundrect_rratio 0.25)
      (net 93 "INIT_B") (pintype "passive"))
  )
	(footprint "data-center-rdimm-ddr4-tester-footprints:R_0402_1005Metric" (layer "B.Cu")
    (at 241.5 97.8 180)
    (descr "Resistor SMD 0402")
    (tags "resistor SMD 0402")
    (property "Author" "Antmicro")
    (property "License" "Apache-2.0")
    (property "MPN" "CR0402-FX-3300GLF")
    (property "Manufacturer" "Bourns")
    (property "Sheetfile" "interfaces.kicad_sch")
    (property "Sheetname" "Interfaces")
    (property "Tolerance" "1%")
    (property "Val" "330R")
    (property "ki_description" "330R resistor in 0402 package with 1% tolerance")
    (attr smd)
    (fp_text reference "R50" (at -1.04 -1.27) (layer "B.SilkS")
        (effects (font (size 0.7 0.7) (thickness 0.15)) (justify left bottom mirror))
    )
    (fp_text value "R_330R_0402" (at 0 -1.4) (layer "B.Fab") hide
        (effects (font (size 0.7 0.7) (thickness 0.15)) (justify left bottom mirror))
    )
    (fp_text user "License: Apache-2.0" (at -0.95 -5.169) (layer "B.Fab") hide
        (effects (font (size 0.7 0.7) (thickness 0.15)) (justify left bottom mirror))
    )
    (fp_text user "${REFERENCE}" (at -0.95 -3.168) (layer "B.Fab") hide
        (effects (font (size 0.7 0.7) (thickness 0.15)) (justify left bottom mirror))
    )
    (fp_text user "Author: Antmicro" (at -0.95 -4.169) (layer "B.Fab") hide
        (effects (font (size 0.7 0.7) (thickness 0.15)) (justify left bottom mirror))
    )
    (fp_rect (start -0.93 0.47) (end 0.93 -0.47)
      (stroke (width 0.05) (type solid)) (fill none) (layer "B.CrtYd"))
    (fp_rect (start -0.5 0.25) (end 0.5 -0.25)
      (stroke (width 0.15) (type solid)) (fill none) (layer "B.Fab"))
    (pad "1" smd roundrect (at -0.485 0 180) (size 0.59 0.64) (layers "B.Cu" "B.Paste" "B.Mask") (roundrect_rratio 0.25)
      (net 63 "Net-(D5-Pad2)") (pintype "passive"))
    (pad "2" smd roundrect (at 0.485 0 180) (size 0.59 0.64) (layers "B.Cu" "B.Paste" "B.Mask") (roundrect_rratio 0.25)
      (net 574 "Net-(Q2-D)") (pintype "passive"))
  )
	(footprint "data-center-rdimm-ddr4-tester-footprints:R_0402_1005Metric" (layer "B.Cu")
    (at 241.5 92.6 180)
    (descr "Resistor SMD 0402")
    (tags "resistor SMD 0402")
    (property "Author" "Antmicro")
    (property "License" "Apache-2.0")
    (property "MPN" "CR0402-FX-3300GLF")
    (property "Manufacturer" "Bourns")
    (property "Sheetfile" "interfaces.kicad_sch")
    (property "Sheetname" "Interfaces")
    (property "Tolerance" "1%")
    (property "Val" "330R")
    (property "ki_description" "330R resistor in 0402 package with 1% tolerance")
    (attr smd)
    (fp_text reference "R51" (at -1.04 -1.27) (layer "B.SilkS")
        (effects (font (size 0.7 0.7) (thickness 0.15)) (justify left bottom mirror))
    )
    (fp_text value "R_330R_0402" (at 0 -1.4) (layer "B.Fab") hide
        (effects (font (size 0.7 0.7) (thickness 0.15)) (justify left bottom mirror))
    )
    (fp_text user "Author: Antmicro" (at -0.95 -4.169) (layer "B.Fab") hide
        (effects (font (size 0.7 0.7) (thickness 0.15)) (justify left bottom mirror))
    )
    (fp_text user "${REFERENCE}" (at -0.95 -3.168) (layer "B.Fab") hide
        (effects (font (size 0.7 0.7) (thickness 0.15)) (justify left bottom mirror))
    )
    (fp_text user "License: Apache-2.0" (at -0.95 -5.169) (layer "B.Fab") hide
        (effects (font (size 0.7 0.7) (thickness 0.15)) (justify left bottom mirror))
    )
    (fp_rect (start -0.93 0.47) (end 0.93 -0.47)
      (stroke (width 0.05) (type solid)) (fill none) (layer "B.CrtYd"))
    (fp_rect (start -0.5 0.25) (end 0.5 -0.25)
      (stroke (width 0.15) (type solid)) (fill none) (layer "B.Fab"))
    (pad "1" smd roundrect (at -0.485 0 180) (size 0.59 0.64) (layers "B.Cu" "B.Paste" "B.Mask") (roundrect_rratio 0.25)
      (net 64 "Net-(D6-Pad2)") (pintype "passive"))
    (pad "2" smd roundrect (at 0.485 0 180) (size 0.59 0.64) (layers "B.Cu" "B.Paste" "B.Mask") (roundrect_rratio 0.25)
      (net 575 "Net-(Q3-D)") (pintype "passive"))
  )
	(footprint "data-center-rdimm-ddr4-tester-footprints:R_0402_1005Metric" (layer "B.Cu")
    (at 241.5 95.35 180)
    (descr "Resistor SMD 0402")
    (tags "resistor SMD 0402")
    (property "Author" "Antmicro")
    (property "License" "Apache-2.0")
    (property "MPN" "CR0402-FX-3300GLF")
    (property "Manufacturer" "Bourns")
    (property "Sheetfile" "interfaces.kicad_sch")
    (property "Sheetname" "Interfaces")
    (property "Tolerance" "1%")
    (property "Val" "330R")
    (property "ki_description" "330R resistor in 0402 package with 1% tolerance")
    (attr smd)
    (fp_text reference "R52" (at -1.04 -1.27) (layer "B.SilkS")
        (effects (font (size 0.7 0.7) (thickness 0.15)) (justify left bottom mirror))
    )
    (fp_text value "R_330R_0402" (at 0 -1.4) (layer "B.Fab") hide
        (effects (font (size 0.7 0.7) (thickness 0.15)) (justify left bottom mirror))
    )
    (fp_text user "License: Apache-2.0" (at -0.95 -5.169) (layer "B.Fab") hide
        (effects (font (size 0.7 0.7) (thickness 0.15)) (justify left bottom mirror))
    )
    (fp_text user "Author: Antmicro" (at -0.95 -4.169) (layer "B.Fab") hide
        (effects (font (size 0.7 0.7) (thickness 0.15)) (justify left bottom mirror))
    )
    (fp_text user "${REFERENCE}" (at -0.95 -3.168) (layer "B.Fab") hide
        (effects (font (size 0.7 0.7) (thickness 0.15)) (justify left bottom mirror))
    )
    (fp_rect (start -0.93 0.47) (end 0.93 -0.47)
      (stroke (width 0.05) (type solid)) (fill none) (layer "B.CrtYd"))
    (fp_rect (start -0.5 0.25) (end 0.5 -0.25)
      (stroke (width 0.15) (type solid)) (fill none) (layer "B.Fab"))
    (pad "1" smd roundrect (at -0.485 0 180) (size 0.59 0.64) (layers "B.Cu" "B.Paste" "B.Mask") (roundrect_rratio 0.25)
      (net 65 "Net-(D7-Pad2)") (pintype "passive"))
    (pad "2" smd roundrect (at 0.485 0 180) (size 0.59 0.64) (layers "B.Cu" "B.Paste" "B.Mask") (roundrect_rratio 0.25)
      (net 576 "Net-(Q4-D)") (pintype "passive"))
  )
	(footprint "data-center-rdimm-ddr4-tester-footprints:R_0402_1005Metric" locked (layer "B.Cu")
    (at 241.5 89.9 180)
    (descr "Resistor SMD 0402")
    (tags "resistor SMD 0402")
    (property "Author" "Antmicro")
    (property "License" "Apache-2.0")
    (property "MPN" "CR0402-FX-3300GLF")
    (property "Manufacturer" "Bourns")
    (property "Sheetfile" "interfaces.kicad_sch")
    (property "Sheetname" "Interfaces")
    (property "Tolerance" "1%")
    (property "Val" "330R")
    (property "ki_description" "330R resistor in 0402 package with 1% tolerance")
    (attr smd)
    (fp_text reference "R53" (at -1.04 -1.27) (layer "B.SilkS")
        (effects (font (size 0.7 0.7) (thickness 0.15)) (justify left bottom mirror))
    )
    (fp_text value "R_330R_0402" (at 0 -1.4) (layer "B.Fab") hide
        (effects (font (size 0.7 0.7) (thickness 0.15)) (justify left bottom mirror))
    )
    (fp_text user "${REFERENCE}" (at -0.95 -3.168) (layer "B.Fab") hide
        (effects (font (size 0.7 0.7) (thickness 0.15)) (justify left bottom mirror))
    )
    (fp_text user "Author: Antmicro" (at -0.95 -4.169) (layer "B.Fab") hide
        (effects (font (size 0.7 0.7) (thickness 0.15)) (justify left bottom mirror))
    )
    (fp_text user "License: Apache-2.0" (at -0.95 -5.169) (layer "B.Fab") hide
        (effects (font (size 0.7 0.7) (thickness 0.15)) (justify left bottom mirror))
    )
    (fp_rect (start -0.93 0.47) (end 0.93 -0.47)
      (stroke (width 0.05) (type solid)) (fill none) (layer "B.CrtYd"))
    (fp_rect (start -0.5 0.25) (end 0.5 -0.25)
      (stroke (width 0.15) (type solid)) (fill none) (layer "B.Fab"))
    (pad "1" smd roundrect locked (at -0.485 0 180) (size 0.59 0.64) (layers "B.Cu" "B.Paste" "B.Mask") (roundrect_rratio 0.25)
      (net 66 "Net-(D8-Pad2)") (pintype "passive"))
    (pad "2" smd roundrect locked (at 0.485 0 180) (size 0.59 0.64) (layers "B.Cu" "B.Paste" "B.Mask") (roundrect_rratio 0.25)
      (net 577 "Net-(Q5-D)") (pintype "passive"))
  )
	(footprint "data-center-rdimm-ddr4-tester-footprints:R_0402_1005Metric" (layer "B.Cu")
    (at 241.5 84.5 180)
    (descr "Resistor SMD 0402")
    (tags "resistor SMD 0402")
    (property "Author" "Antmicro")
    (property "License" "Apache-2.0")
    (property "MPN" "CR0402-FX-3300GLF")
    (property "Manufacturer" "Bourns")
    (property "Sheetfile" "interfaces.kicad_sch")
    (property "Sheetname" "Interfaces")
    (property "Tolerance" "1%")
    (property "Val" "330R")
    (property "ki_description" "330R resistor in 0402 package with 1% tolerance")
    (attr smd)
    (fp_text reference "R54" (at -1.05 -1.36) (layer "B.SilkS")
        (effects (font (size 0.7 0.7) (thickness 0.15)) (justify left bottom mirror))
    )
    (fp_text value "R_330R_0402" (at 0 -1.4) (layer "B.Fab") hide
        (effects (font (size 0.7 0.7) (thickness 0.15)) (justify left bottom mirror))
    )
    (fp_text user "Author: Antmicro" (at -0.95 -4.169) (layer "B.Fab") hide
        (effects (font (size 0.7 0.7) (thickness 0.15)) (justify left bottom mirror))
    )
    (fp_text user "License: Apache-2.0" (at -0.95 -5.169) (layer "B.Fab") hide
        (effects (font (size 0.7 0.7) (thickness 0.15)) (justify left bottom mirror))
    )
    (fp_text user "${REFERENCE}" (at -0.95 -3.168) (layer "B.Fab") hide
        (effects (font (size 0.7 0.7) (thickness 0.15)) (justify left bottom mirror))
    )
    (fp_rect (start -0.93 0.47) (end 0.93 -0.47)
      (stroke (width 0.05) (type solid)) (fill none) (layer "B.CrtYd"))
    (fp_rect (start -0.5 0.25) (end 0.5 -0.25)
      (stroke (width 0.15) (type solid)) (fill none) (layer "B.Fab"))
    (pad "1" smd roundrect (at -0.485 0 180) (size 0.59 0.64) (layers "B.Cu" "B.Paste" "B.Mask") (roundrect_rratio 0.25)
      (net 78 "Net-(D9-Pad2)") (pintype "passive"))
    (pad "2" smd roundrect (at 0.485 0 180) (size 0.59 0.64) (layers "B.Cu" "B.Paste" "B.Mask") (roundrect_rratio 0.25)
      (net 578 "Net-(Q6-D)") (pintype "passive"))
  )
)
